# S9S_MB_2U (Grand Teton) — schematic netlist excerpt (pin names and nets, part order shuffled) for the footprints in the layout excerpt that follows; sources: Cadence DE-HDL packaged netlist, KiCad conversion of 03242023_DA0F0TMBIJ0_F0T_Motherboard_J_brd_V01_OCP.brd

PR3822  Q_RES  5.36K 1% CHIP  pkg 0402LF  page 162 : A = P3V3_OCP_CB_2 ; B = GND

(kicad_pcb
	(version 20260206)
	(generator "pcbnew")
	(generator_version "10.0")
	(general
		(thickness 1.6)
		(legacy_teardrops no)
	)
	(paper "A4")
	(title_block
		(title "03242023_DA0F0TMBIJ0_F0T_Motherboard_J_brd_V01_OCP.brd")
		(comment 1 "Grand Teton / footprints 3161-3161 of 6105")
	)
	(layers
		(0 "F.Cu" signal "TOP")
		(4 "In1.Cu" signal "GND")
		(6 "In2.Cu" signal "IN1")
		(8 "In3.Cu" signal "GND1")
		(10 "In4.Cu" signal "IN2")
		(12 "In5.Cu" signal "GND2")
		(14 "In6.Cu" signal "IN3")
		(16 "In7.Cu" signal "GND3")
		(18 "In8.Cu" signal "VCC")
		(20 "In9.Cu" signal "VCC1")
		(22 "In10.Cu" signal "GND4")
		(24 "In11.Cu" signal "IN4")
		(26 "In12.Cu" signal "GND5")
		(28 "In13.Cu" signal "IN5")
		(30 "In14.Cu" signal "GND6")
		(32 "In15.Cu" signal "IN6")
		(34 "In16.Cu" signal "GND7")
		(2 "B.Cu" signal "BOTTOM")
		(9 "F.Adhes" user "F.Adhesive")
		(11 "B.Adhes" user "B.Adhesive")
		(13 "F.Paste" user "Package Geometry/Pastemask Top")
		(15 "B.Paste" user "Package Geometry/Pastemask Bottom")
		(5 "F.SilkS" user "Ref Des/Silkscreen Top")
		(7 "B.SilkS" user "Ref Des/Silkscreen Bottom")
		(1 "F.Mask" user "Board Geometry/Soldermask Top")
		(3 "B.Mask" user "Board Geometry/Soldermask Bottom")
		(17 "Dwgs.User" user "User.Drawings")
		(19 "Cmts.User" user "User.Comments")
		(21 "Eco1.User" user "User.Eco1")
		(23 "Eco2.User" user "User.Eco2")
		(25 "Edge.Cuts" user "Board Geometry/Outline")
		(27 "Margin" user)
		(31 "F.CrtYd" user "Package Geometry/Place Bound Top")
		(29 "B.CrtYd" user "Package Geometry/Place Bound Bottom")
		(35 "F.Fab" user "Ref Des/Assembly Top")
		(33 "B.Fab" user "Ref Des/Assembly Bottom")
	)
	(footprint ""
		(layer "F.Cu")
		(at 83.55711 -59.242706 90)
		(property "Reference" "PR3822"
			(at 0 0 90)
			(layer "F.SilkS")
			(hide yes)
			(effects
				(font
					(size 1.27 1.27)
				)
			)
		)
		(property "Value" ""
			(at 0 0 90)
			(layer "F.Fab")
			(effects
				(font
					(size 1.27 1.27)
				)
			)
		)
		(duplicate_pad_numbers_are_jumpers no)
		(fp_line
			(start 0.7874 -0.4064)
			(end 0.7874 0.4064)
			(stroke
				(width 0.1524)
				(type default)
			)
			(layer "F.SilkS")
		)
		(fp_line
			(start -0.7874 -0.4064)
			(end 0.7874 -0.4064)
			(stroke
				(width 0.1524)
				(type default)
			)
			(layer "F.SilkS")
		)
		(fp_line
			(start 0.7874 0.4064)
			(end -0.7874 0.4064)
			(stroke
				(width 0.1524)
				(type default)
			)
			(layer "F.SilkS")
		)
		(fp_line
			(start -0.7874 0.4064)
			(end -0.7874 -0.4064)
			(stroke
				(width 0.1524)
				(type default)
			)
			(layer "F.SilkS")
		)
		(fp_line
			(start -0.12065 -0.305054)
			(end -0.12065 -0.2794)
			(stroke
				(width 0.1)
				(type default)
			)
			(layer "F.Fab")
		)
		(fp_line
			(start -0.67945 -0.305054)
			(end -0.12065 -0.305054)
			(stroke
				(width 0.1)
				(type default)
			)
			(layer "F.Fab")
		)
		(fp_line
			(start 0.67945 -0.3048)
			(end 0.67945 0.3048)
			(stroke
				(width 0.1)
				(type default)
			)
			(layer "F.Fab")
		)
		(fp_line
			(start 0.12065 -0.3048)
			(end 0.67945 -0.3048)
			(stroke
				(width 0.1)
				(type default)
			)
			(layer "F.Fab")
		)
		(fp_line
			(start 0.12065 -0.2794)
			(end 0.12065 -0.3048)
			(stroke
				(width 0.1)
				(type default)
			)
			(layer "F.Fab")
		)
		(fp_line
			(start -0.12065 -0.2794)
			(end 0.12065 -0.2794)
			(stroke
				(width 0.1)
				(type default)
			)
			(layer "F.Fab")
		)
		(fp_line
			(start 0.120396 0.2794)
			(end -0.12065 0.2794)
			(stroke
				(width 0.1)
				(type default)
			)
			(layer "F.Fab")
		)
		(fp_line
			(start -0.12065 0.2794)
			(end -0.12065 0.3048)
			(stroke
				(width 0.1)
				(type default)
			)
			(layer "F.Fab")
		)
		(fp_line
			(start 0.67945 0.3048)
			(end 0.120396 0.3048)
			(stroke
				(width 0.1)
				(type default)
			)
			(layer "F.Fab")
		)
		(fp_line
			(start 0.120396 0.3048)
			(end 0.120396 0.2794)
			(stroke
				(width 0.1)
				(type default)
			)
			(layer "F.Fab")
		)
		(fp_line
			(start -0.12065 0.3048)
			(end -0.67945 0.3048)
			(stroke
				(width 0.1)
				(type default)
			)
			(layer "F.Fab")
		)
		(fp_line
			(start -0.67945 0.3048)
			(end -0.67945 -0.305054)
			(stroke
				(width 0.1)
				(type default)
			)
			(layer "F.Fab")
		)
		(pad "1" smd circle
			(at -0.40005 0 90)
			(size 0 0)
			(layers "F.Cu" "F.Mask" "F.Paste")
			(net "P3V3_OCP_CB_2")
		)
		(pad "2" smd circle
			(at 0.40005 0 90)
			(size 0 0)
			(layers "F.Cu" "F.Mask" "F.Paste")
			(net "GND")
		)
	)
)
